# SCM (Grand Teton) — schematic netlist excerpt (pin names and nets, part order shuffled) for the footprints in the layout excerpt that follows; sources: Cadence DE-HDL packaged netlist, KiCad conversion of 12092022_DA0F0TMDCD0_F0T_Management_Board_D_brd_V3_OCP.brd

R554  Q_RES  4.7K 1% EMPTY  pkg 0402LF  page 25 : A = P3V3_AUX ; B = FLASH_R_WP_STATUS
PR543  Q_RES  100K 1% CHIP  pkg 0402LF  page 56 : A = P1V0_AUX_MODE ; B = GND

(kicad_pcb
	(version 20260206)
	(generator "pcbnew")
	(generator_version "10.0")
	(general
		(thickness 1.6)
		(legacy_teardrops no)
	)
	(paper "A4")
	(title_block
		(title "12092022_DA0F0TMDCD0_F0T_Management_Board_D_brd_V3_OCP.brd")
		(comment 1 "Grand Teton / footprints 231-232 of 1440")
	)
	(layers
		(0 "F.Cu" signal "TOP")
		(4 "In1.Cu" signal "GND")
		(6 "In2.Cu" signal "IN1")
		(8 "In3.Cu" signal "GND1")
		(10 "In4.Cu" signal "IN2")
		(12 "In5.Cu" signal "VCC")
		(14 "In6.Cu" signal "VCC1")
		(16 "In7.Cu" signal "IN3")
		(18 "In8.Cu" signal "GND2")
		(20 "In9.Cu" signal "IN4")
		(22 "In10.Cu" signal "GND3")
		(2 "B.Cu" signal "BOTTOM")
		(9 "F.Adhes" user "F.Adhesive")
		(11 "B.Adhes" user "B.Adhesive")
		(13 "F.Paste" user "Package Geometry/Pastemask Top")
		(15 "B.Paste" user "Package Geometry/Pastemask Bottom")
		(5 "F.SilkS" user "Ref Des/Silkscreen Top")
		(7 "B.SilkS" user "Ref Des/Silkscreen Bottom")
		(1 "F.Mask" user "Board Geometry/Soldermask Top")
		(3 "B.Mask" user "Board Geometry/Soldermask Bottom")
		(17 "Dwgs.User" user "User.Drawings")
		(19 "Cmts.User" user "User.Comments")
		(21 "Eco1.User" user "User.Eco1")
		(23 "Eco2.User" user "User.Eco2")
		(25 "Edge.Cuts" user "Board Geometry/Outline")
		(27 "Margin" user)
		(31 "F.CrtYd" user "Package Geometry/Place Bound Top")
		(29 "B.CrtYd" user "Package Geometry/Place Bound Bottom")
		(35 "F.Fab" user "Ref Des/Assembly Top")
		(33 "B.Fab" user "Ref Des/Assembly Bottom")
	)
	(footprint ""
		(layer "F.Cu")
		(at 16.50365 -29.5783 180)
		(property "Reference" "PR543"
			(at 0 0 180)
			(layer "F.SilkS")
			(hide yes)
			(effects
				(font
					(size 1.27 1.27)
				)
			)
		)
		(property "Value" ""
			(at 0 0 180)
			(layer "F.Fab")
			(effects
				(font
					(size 1.27 1.27)
				)
			)
		)
		(duplicate_pad_numbers_are_jumpers no)
		(fp_line
			(start 0.7874 0.4064)
			(end -0.7874 0.4064)
			(stroke
				(width 0.1524)
				(type default)
			)
			(layer "F.SilkS")
		)
		(fp_line
			(start 0.7874 -0.4064)
			(end 0.7874 0.4064)
			(stroke
				(width 0.1524)
				(type default)
			)
			(layer "F.SilkS")
		)
		(fp_line
			(start -0.7874 0.4064)
			(end -0.7874 -0.4064)
			(stroke
				(width 0.1524)
				(type default)
			)
			(layer "F.SilkS")
		)
		(fp_line
			(start -0.7874 -0.4064)
			(end 0.7874 -0.4064)
			(stroke
				(width 0.1524)
				(type default)
			)
			(layer "F.SilkS")
		)
		(fp_line
			(start 0.67945 0.3048)
			(end 0.120396 0.3048)
			(stroke
				(width 0.1)
				(type default)
			)
			(layer "F.Fab")
		)
		(fp_line
			(start 0.67945 -0.3048)
			(end 0.67945 0.3048)
			(stroke
				(width 0.1)
				(type default)
			)
			(layer "F.Fab")
		)
		(fp_line
			(start 0.12065 -0.2794)
			(end 0.12065 -0.3048)
			(stroke
				(width 0.1)
				(type default)
			)
			(layer "F.Fab")
		)
		(fp_line
			(start 0.12065 -0.3048)
			(end 0.67945 -0.3048)
			(stroke
				(width 0.1)
				(type default)
			)
			(layer "F.Fab")
		)
		(fp_line
			(start 0.120396 0.3048)
			(end 0.120396 0.2794)
			(stroke
				(width 0.1)
				(type default)
			)
			(layer "F.Fab")
		)
		(fp_line
			(start 0.120396 0.2794)
			(end -0.12065 0.2794)
			(stroke
				(width 0.1)
				(type default)
			)
			(layer "F.Fab")
		)
		(fp_line
			(start -0.12065 0.3048)
			(end -0.67945 0.3048)
			(stroke
				(width 0.1)
				(type default)
			)
			(layer "F.Fab")
		)
		(fp_line
			(start -0.12065 0.2794)
			(end -0.12065 0.3048)
			(stroke
				(width 0.1)
				(type default)
			)
			(layer "F.Fab")
		)
		(fp_line
			(start -0.12065 -0.2794)
			(end 0.12065 -0.2794)
			(stroke
				(width 0.1)
				(type default)
			)
			(layer "F.Fab")
		)
		(fp_line
			(start -0.12065 -0.305054)
			(end -0.12065 -0.2794)
			(stroke
				(width 0.1)
				(type default)
			)
			(layer "F.Fab")
		)
		(fp_line
			(start -0.67945 0.3048)
			(end -0.67945 -0.305054)
			(stroke
				(width 0.1)
				(type default)
			)
			(layer "F.Fab")
		)
		(fp_line
			(start -0.67945 -0.305054)
			(end -0.12065 -0.305054)
			(stroke
				(width 0.1)
				(type default)
			)
			(layer "F.Fab")
		)
		(pad "1" smd circle
			(at -0.40005 0 180)
			(size 0 0)
			(layers "F.Cu" "F.Mask" "F.Paste")
			(net "P1V0_AUX_MODE")
		)
		(pad "2" smd circle
			(at 0.40005 0 180)
			(size 0 0)
			(layers "F.Cu" "F.Mask" "F.Paste")
			(net "GND")
		)
	)
	(footprint ""
		(layer "F.Cu")
		(at 56.0324 -82.8802 -90)
		(property "Reference" "R554"
			(at 0 0 270)
			(layer "F.SilkS")
			(hide yes)
			(effects
				(font
					(size 1.27 1.27)
				)
			)
		)
		(property "Value" ""
			(at 0 0 270)
			(layer "F.Fab")
			(effects
				(font
					(size 1.27 1.27)
				)
			)
		)
		(duplicate_pad_numbers_are_jumpers no)
		(fp_line
			(start -0.7874 0.4064)
			(end -0.7874 -0.4064)
			(stroke
				(width 0.1524)
				(type default)
			)
			(layer "F.SilkS")
		)
		(fp_line
			(start 0.7874 0.4064)
			(end -0.7874 0.4064)
			(stroke
				(width 0.1524)
				(type default)
			)
			(layer "F.SilkS")
		)
		(fp_line
			(start -0.7874 -0.4064)
			(end 0.7874 -0.4064)
			(stroke
				(width 0.1524)
				(type default)
			)
			(layer "F.SilkS")
		)
		(fp_line
			(start 0.7874 -0.4064)
			(end 0.7874 0.4064)
			(stroke
				(width 0.1524)
				(type default)
			)
			(layer "F.SilkS")
		)
		(fp_line
			(start -0.67945 0.3048)
			(end -0.67945 -0.305054)
			(stroke
				(width 0.1)
				(type default)
			)
			(layer "F.Fab")
		)
		(fp_line
			(start -0.12065 0.3048)
			(end -0.67945 0.3048)
			(stroke
				(width 0.1)
				(type default)
			)
			(layer "F.Fab")
		)
		(fp_line
			(start 0.120396 0.3048)
			(end 0.120396 0.2794)
			(stroke
				(width 0.1)
				(type default)
			)
			(layer "F.Fab")
		)
		(fp_line
			(start 0.67945 0.3048)
			(end 0.120396 0.3048)
			(stroke
				(width 0.1)
				(type default)
			)
			(layer "F.Fab")
		)
		(fp_line
			(start -0.12065 0.2794)
			(end -0.12065 0.3048)
			(stroke
				(width 0.1)
				(type default)
			)
			(layer "F.Fab")
		)
		(fp_line
			(start 0.120396 0.2794)
			(end -0.12065 0.2794)
			(stroke
				(width 0.1)
				(type default)
			)
			(layer "F.Fab")
		)
		(fp_line
			(start -0.12065 -0.2794)
			(end 0.12065 -0.2794)
			(stroke
				(width 0.1)
				(type default)
			)
			(layer "F.Fab")
		)
		(fp_line
			(start 0.12065 -0.2794)
			(end 0.12065 -0.3048)
			(stroke
				(width 0.1)
				(type default)
			)
			(layer "F.Fab")
		)
		(fp_line
			(start 0.12065 -0.3048)
			(end 0.67945 -0.3048)
			(stroke
				(width 0.1)
				(type default)
			)
			(layer "F.Fab")
		)
		(fp_line
			(start 0.67945 -0.3048)
			(end 0.67945 0.3048)
			(stroke
				(width 0.1)
				(type default)
			)
			(layer "F.Fab")
		)
		(fp_line
			(start -0.67945 -0.305054)
			(end -0.12065 -0.305054)
			(stroke
				(width 0.1)
				(type default)
			)
			(layer "F.Fab")
		)
		(fp_line
			(start -0.12065 -0.305054)
			(end -0.12065 -0.2794)
			(stroke
				(width 0.1)
				(type default)
			)
			(layer "F.Fab")
		)
		(pad "1" smd circle
			(at -0.40005 0 270)
			(size 0 0)
			(layers "F.Cu" "F.Mask" "F.Paste")
			(net "P3V3_AUX")
		)
		(pad "2" smd circle
			(at 0.40005 0 270)
			(size 0 0)
			(layers "F.Cu" "F.Mask" "F.Paste")
			(net "FLASH_R_WP_STATUS")
		)
	)
)
